# BASEBOARD_FAB2 (Tioga Pass) — schematic netlist excerpt (pin names and nets, part order shuffled) for the footprints in the layout excerpt that follows; sources: Cadence DE-HDL packaged netlist, KiCad conversion of Wiwynn_Tioga_Pass_MB.brd

EU1D1  IR354XX  IR35411 IC  pkg SM  page 208
  VOS  = PVCCIN_CPU1
  LGND  = GND
  VCC  = VR_PVCCIN_CPU1_PH4_VCIN
  VDRV  = P5V_STBY
  PGND(0)  = GND
  GL(0)  = TP_PVCCIN_CPU1_PH4_GL_0
  PGND(1)  = GND
  SW  = VR_PVCCIN_CPU1_PHASE4
  VIN(0)  = VR_FET_SW_P12V_STBY_PVCCIN_CPU1
  VIN(1)  = VR_FET_SW_P12V_STBY_PVCCIN_CPU1
  NC  = NC
  PHASE  = VR_PVCCIN_CPU1_PH4_PHASE
  BOOST  = VR_PVCCIN_CPU1_PH4_BOOT_R
  PWM  = VR_PVCCIN_CPU1_PWM4
  EN  = P5V_STBY
  TOUT_FLT  = A_TSENSE_PVCCIN_CPU1
  OCSET  = VR_PVCCIN_CPU1_PH4_OCSET
  IOUT  = ISENSE_PVCCIN_CPU1_PH4_IMON
  REFIN  = VR_PVCCIN_CPU1_AIREF4
  PGND(2)  = GND
  GL(1)  = TP_PVCCIN_CPU1_PH4_GL_1

(kicad_pcb
	(version 20260206)
	(generator "pcbnew")
	(generator_version "10.0")
	(general
		(thickness 1.6)
		(legacy_teardrops no)
	)
	(paper "A4")
	(title_block
		(title "Wiwynn_Tioga_Pass_MB.brd")
		(comment 1 "Tioga Pass / footprints 1311-1311 of 4770")
	)
	(layers
		(0 "F.Cu" signal "TOP")
		(4 "In1.Cu" signal "L2GND")
		(6 "In2.Cu" signal "L3")
		(8 "In3.Cu" signal "L4GND")
		(10 "In4.Cu" signal "L5")
		(12 "In5.Cu" signal "L6GND")
		(14 "In6.Cu" signal "L7VCC")
		(16 "In7.Cu" signal "L8VCC")
		(18 "In8.Cu" signal "L9GND")
		(20 "In9.Cu" signal "L10")
		(22 "In10.Cu" signal "L11GND")
		(24 "In11.Cu" signal "L12")
		(26 "In12.Cu" signal "L13GND")
		(2 "B.Cu" signal "BOTTOM")
		(9 "F.Adhes" user "F.Adhesive")
		(11 "B.Adhes" user "B.Adhesive")
		(13 "F.Paste" user "Package Geometry/Pastemask Top")
		(15 "B.Paste" user "Package Geometry/Pastemask Bottom")
		(5 "F.SilkS" user "Ref Des/Silkscreen Top")
		(7 "B.SilkS" user "Ref Des/Silkscreen Bottom")
		(1 "F.Mask" user "Board Geometry/Soldermask Top")
		(3 "B.Mask" user "Board Geometry/Soldermask Bottom")
		(17 "Dwgs.User" user "User.Drawings")
		(19 "Cmts.User" user "User.Comments")
		(21 "Eco1.User" user "User.Eco1")
		(23 "Eco2.User" user "User.Eco2")
		(25 "Edge.Cuts" user "Board Geometry/Outline")
		(27 "Margin" user)
		(31 "F.CrtYd" user "Package Geometry/Place Bound Top")
		(29 "B.CrtYd" user "Package Geometry/Place Bound Bottom")
		(35 "F.Fab" user "Ref Des/Assembly Top")
		(33 "B.Fab" user "Ref Des/Assembly Bottom")
	)
	(footprint ""
		(layer "F.Cu")
		(at 33.925002 -81.423764 90)
		(property "Reference" "EU1D1"
			(at 3.334766 -1.565402 0)
			(unlocked yes)
			(layer "F.SilkS")
			(effects
				(font
					(size 0.7874 0.5842)
					(thickness 0.1524)
				)
			)
		)
		(property "Value" ""
			(at 0 0 90)
			(layer "F.Fab")
			(effects
				(font
					(size 1.27 1.27)
				)
			)
		)
		(duplicate_pad_numbers_are_jumpers no)
		(fp_line
			(start 2.9718 -3.5052)
			(end 2.9718 3.429)
			(stroke
				(width 0.1524)
				(type default)
			)
			(layer "F.SilkS")
		)
		(fp_line
			(start -3.0099 -3.5052)
			(end 2.9718 -3.5052)
			(stroke
				(width 0.1524)
				(type default)
			)
			(layer "F.SilkS")
		)
		(fp_line
			(start 2.9718 3.429)
			(end -3.0099 3.429)
			(stroke
				(width 0.1524)
				(type default)
			)
			(layer "F.SilkS")
		)
		(fp_line
			(start -3.0099 3.429)
			(end -3.0099 -3.5052)
			(stroke
				(width 0.1524)
				(type default)
			)
			(layer "F.SilkS")
		)
		(fp_circle
			(center -3.057398 -2.678684)
			(end -3.057398 -2.551684)
			(stroke
				(width 0.254)
				(type default)
			)
			(fill no)
			(layer "F.SilkS")
		)
		(fp_poly
			(pts
				(xy -2.9972 -3.4925) (xy -2.9972 -2.6924) (xy -2.1971 -3.4925)
			)
			(stroke
				(width 0)
				(type default)
			)
			(fill yes)
			(layer "F.SilkS")
		)
		(fp_poly
			(pts
				(xy -2.549906 -3.050032) (xy -2.549906 3.050032) (xy 2.549906 3.050032) (xy 2.549906 -3.050032)
			)
			(stroke
				(width 0)
				(type default)
			)
			(fill no)
			(layer "F.CrtYd")
		)
		(fp_line
			(start 2.549906 -3.050032)
			(end 2.549906 3.050032)
			(stroke
				(width 0.1)
				(type default)
			)
			(layer "F.Fab")
		)
		(fp_line
			(start -2.549906 -3.050032)
			(end 2.549906 -3.050032)
			(stroke
				(width 0.1)
				(type default)
			)
			(layer "F.Fab")
		)
		(fp_line
			(start 2.549906 3.050032)
			(end -2.549906 3.050032)
			(stroke
				(width 0.1)
				(type default)
			)
			(layer "F.Fab")
		)
		(fp_line
			(start -2.549906 3.050032)
			(end -2.549906 -3.050032)
			(stroke
				(width 0.1)
				(type default)
			)
			(layer "F.Fab")
		)
		(fp_circle
			(center -3.057398 -2.678684)
			(end -3.057398 -2.551684)
			(stroke
				(width 0.254)
				(type default)
			)
			(fill no)
			(layer "F.Fab")
		)
		(pad "1" smd rect
			(at -2.39522 -2.279904 90)
			(size 0.7112 0.254)
			(layers "F.Cu" "F.Mask" "F.Paste")
			(net "PVCCIN_CPU1")
		)
		(pad "2" smd rect
			(at -2.39522 -1.83007 90)
			(size 0.7112 0.254)
			(layers "F.Cu" "F.Mask" "F.Paste")
			(net "GND")
		)
		(pad "3" smd rect
			(at -2.39522 -1.379982 90)
			(size 0.7112 0.254)
			(layers "F.Cu" "F.Mask" "F.Paste")
			(net "VR_PVCCIN_CPU1_PH4_VCIN")
		)
		(pad "4" smd rect
			(at -2.39522 -0.929894 90)
			(size 0.7112 0.254)
			(layers "F.Cu" "F.Mask" "F.Paste")
			(net "P5V_STBY")
		)
		(pad "5" smd rect
			(at -2.39522 -0.48006 90)
			(size 0.7112 0.254)
			(layers "F.Cu" "F.Mask" "F.Paste")
			(net "GND")
		)
		(pad "6" smd rect
			(at -2.39522 -0.029972 90)
			(size 0.7112 0.254)
			(layers "F.Cu" "F.Mask" "F.Paste")
			(net "TP_PVCCIN_CPU1_PH4_GL_0")
		)
		(pad "7" smd custom
			(at 0.016764 1.145032 90)
			(size 0.53975 0.53975)
			(layers "F.Cu" "F.Mask" "F.Paste")
			(net "GND")
			(options
				(clearance outline)
				(anchor circle)
			)
			(primitives
				(gr_poly
					(pts
						(xy -2.7051 1.0795) (xy -2.7051 -0.3683) (xy -0.9271 -0.3683) (xy -0.9271 -1.0795) (xy 2.7051 -1.0795)
						(xy 2.7051 1.0795)
					)
					(width 0)
					(fill yes)
				)
			)
		)
		(pad "10" smd rect
			(at -0.008382 2.874772 90)
			(size 4.3434 0.6096)
			(layers "F.Cu" "F.Mask" "F.Paste")
			(net "VR_PVCCIN_CPU1_PHASE4")
		)
		(pad "25" smd rect
			(at 1.548384 -1.283208 90)
			(size 2.3368 2.0066)
			(layers "F.Cu" "F.Mask" "F.Paste")
			(net "VR_FET_SW_P12V_STBY_PVCCIN_CPU1")
		)
		(pad "30" smd rect
			(at 2.050034 -2.895092 90)
			(size 0.254 0.7112)
			(layers "F.Cu" "F.Mask" "F.Paste")
			(net "VR_FET_SW_P12V_STBY_PVCCIN_CPU1")
		)
		(pad "31" smd rect
			(at 1.599946 -2.895092 90)
			(size 0.254 0.7112)
			(layers "F.Cu" "F.Mask" "F.Paste")
			(net "Net_358")
		)
		(pad "32" smd rect
			(at 1.150112 -2.895092 90)
			(size 0.254 0.7112)
			(layers "F.Cu" "F.Mask" "F.Paste")
			(net "VR_PVCCIN_CPU1_PH4_PHASE")
		)
		(pad "33" smd rect
			(at 0.700024 -2.895092 90)
			(size 0.254 0.7112)
			(layers "F.Cu" "F.Mask" "F.Paste")
			(net "VR_PVCCIN_CPU1_PH4_BOOT_R")
		)
		(pad "34" smd rect
			(at 0.249936 -2.895092 90)
			(size 0.254 0.7112)
			(layers "F.Cu" "F.Mask" "F.Paste")
			(net "VR_PVCCIN_CPU1_PWM4")
		)
		(pad "35" smd rect
			(at -0.199898 -2.895092 90)
			(size 0.254 0.7112)
			(layers "F.Cu" "F.Mask" "F.Paste")
			(net "P5V_STBY")
		)
		(pad "36" smd rect
			(at -0.649986 -2.895092 90)
			(size 0.254 0.7112)
			(layers "F.Cu" "F.Mask" "F.Paste")
			(net "A_TSENSE_PVCCIN_CPU1")
		)
		(pad "37" smd rect
			(at -1.100074 -2.895092 90)
			(size 0.254 0.7112)
			(layers "F.Cu" "F.Mask" "F.Paste")
			(net "VR_PVCCIN_CPU1_PH4_OCSET")
		)
		(pad "38" smd rect
			(at -1.549908 -2.895092 90)
			(size 0.254 0.7112)
			(layers "F.Cu" "F.Mask" "F.Paste")
			(net "ISENSE_PVCCIN_CPU1_PH4_IMON")
		)
		(pad "39" smd rect
			(at -1.999996 -2.895092 90)
			(size 0.254 0.7112)
			(layers "F.Cu" "F.Mask" "F.Paste")
			(net "VR_PVCCIN_CPU1_AIREF4")
		)
		(pad "40" smd rect
			(at -0.871728 -1.283208 90)
			(size 1.8034 2.0066)
			(layers "F.Cu" "F.Mask" "F.Paste")
			(net "GND")
		)
		(pad "41" smd rect
			(at -1.533906 0.247904 90)
			(size 0.508 0.3556)
			(layers "F.Cu" "F.Mask" "F.Paste")
			(net "TP_PVCCIN_CPU1_PH4_GL_1")
		)
	)
)
